# TIMECARD (Time Appliance Project (Time Card)) — schematic netlist excerpt (pin names and nets, part order shuffled) for the footprints in the layout excerpt that follows; sources: Cadence DE-HDL packaged netlist, KiCad conversion of R4006-B0001-02_R01.brd

U27  SHT31A_DIS_B10KS_DFN8  SHT31A-DIS-B10KS  pkg DFN9_098_P0197_TR039X071  page 18
  SDA  = R_SHT3X_I2C_SDA
  ADDR  = SHT3X_ADDR
  ALERT  = R_SHT3X_ALERT_N
  SCL  = R_SHT3X_I2C_SCL
  VDD  = VDD3V3_SHT31A
  \reset*\  = R_SHT3X_RST_N
  R  = SG
  VSS  = SG
  THRM_PAD  = SG

(kicad_pcb
	(version 20260206)
	(generator "pcbnew")
	(generator_version "10.0")
	(general
		(thickness 1.6)
		(legacy_teardrops no)
	)
	(paper "A4")
	(title_block
		(title "timecard-production-celestica-r4006 — R4006-B0001-02_R01.brd")
		(comment 1 "Time Appliance Project (Time Card) / footprints 229-229 of 1113")
	)
	(layers
		(0 "F.Cu" signal "TOP")
		(4 "In1.Cu" signal "L02_GND1")
		(6 "In2.Cu" signal "L03_SIG1")
		(8 "In3.Cu" signal "L04_GND2")
		(10 "In4.Cu" signal "L05_VCC1")
		(12 "In5.Cu" signal "L06_VCC2")
		(14 "In6.Cu" signal "L07_GND3")
		(16 "In7.Cu" signal "L08_SIG2")
		(18 "In8.Cu" signal "L09_GND4")
		(2 "B.Cu" signal "BOTTOM")
		(9 "F.Adhes" user "F.Adhesive")
		(11 "B.Adhes" user "B.Adhesive")
		(13 "F.Paste" user "Package Geometry/Pastemask Top")
		(15 "B.Paste" user "Package Geometry/Pastemask Bottom")
		(5 "F.SilkS" user "Ref Des/Silkscreen Top")
		(7 "B.SilkS" user "Ref Des/Silkscreen Bottom")
		(1 "F.Mask" user "Board Geometry/Soldermask Top")
		(3 "B.Mask" user "Board Geometry/Soldermask Bottom")
		(17 "Dwgs.User" user "User.Drawings")
		(19 "Cmts.User" user "User.Comments")
		(21 "Eco1.User" user "User.Eco1")
		(23 "Eco2.User" user "User.Eco2")
		(25 "Edge.Cuts" user "Board Geometry/Outline")
		(27 "Margin" user)
		(31 "F.CrtYd" user "Package Geometry/Place Bound Top")
		(29 "B.CrtYd" user "Package Geometry/Place Bound Bottom")
		(35 "F.Fab" user "Ref Des/Assembly Top")
		(33 "B.Fab" user "Ref Des/Assembly Bottom")
	)
	(footprint ""
		(layer "F.Cu")
		(at 152.146 -53.1876 90)
		(property "Reference" "U27"
			(at -0.7366 2.45237 90)
			(unlocked yes)
			(layer "F.SilkS")
			(effects
				(font
					(size 0.7874 0.5842)
					(thickness 0.1524)
				)
			)
		)
		(property "Value" ""
			(at 0 0 90)
			(layer "F.Fab")
			(effects
				(font
					(size 1.27 1.27)
				)
			)
		)
		(property "Device Type" "SHT31A_DIS_B10KS_DFN8-A222-000A"
			(at 0 3.831336 90)
			(unlocked yes)
			(layer "F.Fab")
			(hide yes)
			(effects
				(font
					(size 0.7874 0.5842)
					(thickness 0.1524)
				)
			)
		)
		(property "User Part Number" "PARTNUM*"
			(at 0 5.025136 90)
			(unlocked yes)
			(layer "Cmts.User")
			(hide yes)
			(effects
				(font
					(size 0.7874 0.5842)
					(thickness 0.1524)
				)
			)
		)
		(duplicate_pad_numbers_are_jumpers no)
		(fp_line
			(start 2.040128 -1.553972)
			(end 2.040128 1.553972)
			(stroke
				(width 0.1)
				(type default)
			)
			(layer "F.SilkS")
		)
		(fp_line
			(start -2.040128 -1.553972)
			(end 2.040128 -1.553972)
			(stroke
				(width 0.1)
				(type default)
			)
			(layer "F.SilkS")
		)
		(fp_line
			(start 2.040128 1.553972)
			(end -2.040128 1.553972)
			(stroke
				(width 0.1)
				(type default)
			)
			(layer "F.SilkS")
		)
		(fp_line
			(start -2.040128 1.553972)
			(end -2.040128 -1.553972)
			(stroke
				(width 0.1)
				(type default)
			)
			(layer "F.SilkS")
		)
		(fp_poly
			(pts
				(arc
					(start -2.5146 -2.032)
					(mid -2.5146 -3.048)
					(end -2.5146 -2.032)
				)
			)
			(stroke
				(width 0)
				(type default)
			)
			(fill yes)
			(layer "F.SilkS")
		)
		(fp_poly
			(pts
				(xy 0.4953 0.1016) (xy 0.4953 0.9017) (xy -0.22098 0.9017)
				(arc
					(start -0.221742 0.900938)
					(mid -0.054914 0.820246)
					(end 0.0127 0.6477)
				)
				(arc
					(start 0.0127 0.6477)
					(mid -0.061695 0.468095)
					(end -0.2413 0.3937)
				)
				(arc
					(start -0.2413 0.3937)
					(mid -0.412633 0.460187)
					(end -0.494284 0.62484)
				)
				(xy -0.4953 0.62484) (xy -0.4953 0.1016)
			)
			(stroke
				(width 0)
				(type default)
			)
			(fill yes)
			(layer "F.Paste")
		)
		(fp_poly
			(pts
				(xy 0.4953 -0.63754) (xy 0.4953 -0.1016) (xy -0.4953 -0.1016) (xy -0.4953 -0.9017) (xy 0.22606 -0.9017)
				(arc
					(start 0.22606 -0.901192)
					(mid 0.056421 -0.821798)
					(end -0.0127 -0.6477)
				)
				(arc
					(start -0.0127 -0.6477)
					(mid 0.061695 -0.468095)
					(end 0.2413 -0.3937)
				)
				(arc
					(start 0.2413 -0.3937)
					(mid 0.417276 -0.464537)
					(end 0.495046 -0.63754)
				)
			)
			(stroke
				(width 0)
				(type default)
			)
			(fill yes)
			(layer "F.Paste")
		)
		(fp_rect
			(start -2.294128 1.807972)
			(end 2.294128 -1.807972)
			(stroke
				(width 0)
				(type default)
			)
			(fill no)
			(layer "F.CrtYd")
		)
		(fp_line
			(start 1.299972 -1.299972)
			(end -1.299972 -1.299972)
			(stroke
				(width 0.1)
				(type default)
			)
			(layer "F.Fab")
		)
		(fp_line
			(start -1.299972 -1.299972)
			(end -1.299972 1.299972)
			(stroke
				(width 0.1)
				(type default)
			)
			(layer "F.Fab")
		)
		(fp_line
			(start 1.299972 1.299972)
			(end 1.299972 -1.299972)
			(stroke
				(width 0.1)
				(type default)
			)
			(layer "F.Fab")
		)
		(fp_line
			(start -1.299972 1.299972)
			(end 1.299972 1.299972)
			(stroke
				(width 0.1)
				(type default)
			)
			(layer "F.Fab")
		)
		(fp_poly
			(pts
				(arc
					(start -2.3876 -1.143)
					(mid -2.3876 -2.159)
					(end -2.3876 -1.143)
				)
			)
			(stroke
				(width 0)
				(type default)
			)
			(fill yes)
			(layer "F.Fab")
		)
		(fp_text user "8"
			(at 2.4384 -1.86563 90)
			(unlocked yes)
			(layer "F.SilkS")
			(effects
				(font
					(size 0.7874 0.5842)
					(thickness 0.1524)
				)
			)
		)
		(fp_text user "4"
			(at -2.6416 1.43637 90)
			(unlocked yes)
			(layer "F.SilkS")
			(effects
				(font
					(size 0.7874 0.5842)
					(thickness 0.1524)
				)
			)
		)
		(fp_text user "5"
			(at 2.4384 1.56337 90)
			(unlocked yes)
			(layer "F.SilkS")
			(effects
				(font
					(size 0.7874 0.5842)
					(thickness 0.1524)
				)
			)
		)
		(fp_text user "8"
			(at 2.14503 -1.524 0)
			(unlocked yes)
			(layer "F.Fab")
			(effects
				(font
					(size 0.7874 0.5842)
					(thickness 0.1524)
				)
			)
		)
		(fp_text user "5"
			(at 1.89103 1.397 0)
			(unlocked yes)
			(layer "F.Fab")
			(effects
				(font
					(size 0.7874 0.5842)
					(thickness 0.1524)
				)
			)
		)
		(fp_text user "4"
			(at -2.17297 1.905 0)
			(unlocked yes)
			(layer "F.Fab")
			(effects
				(font
					(size 0.7874 0.5842)
					(thickness 0.1524)
				)
			)
		)
		(pad "1" smd rect
			(at -1.265428 -0.750062 90)
			(size 1.0414 0.3048)
			(layers "F.Cu" "F.Mask" "F.Paste")
			(net "R_SHT3X_I2C_SDA")
		)
		(pad "2" smd rect
			(at -1.265428 -0.249936 90)
			(size 1.0414 0.3048)
			(layers "F.Cu" "F.Mask" "F.Paste")
			(net "SHT3X_ADDR")
		)
		(pad "3" smd rect
			(at -1.265428 0.249936 90)
			(size 1.0414 0.3048)
			(layers "F.Cu" "F.Mask" "F.Paste")
			(net "R_SHT3X_ALERT_N")
		)
		(pad "4" smd rect
			(at -1.265428 0.750062 90)
			(size 1.0414 0.3048)
			(layers "F.Cu" "F.Mask" "F.Paste")
			(net "R_SHT3X_I2C_SCL")
		)
		(pad "5" smd rect
			(at 1.265428 0.750062 90)
			(size 1.0414 0.3048)
			(layers "F.Cu" "F.Mask" "F.Paste")
			(net "VDD3V3_SHT31A")
		)
		(pad "6" smd rect
			(at 1.265428 0.249936 90)
			(size 1.0414 0.3048)
			(layers "F.Cu" "F.Mask" "F.Paste")
			(net "R_SHT3X_RST_N")
		)
		(pad "7" smd rect
			(at 1.265428 -0.249936 90)
			(size 1.0414 0.3048)
			(layers "F.Cu" "F.Mask" "F.Paste")
			(net "SG")
		)
		(pad "8" smd rect
			(at 1.265428 -0.750062 90)
			(size 1.0414 0.3048)
			(layers "F.Cu" "F.Mask" "F.Paste")
			(net "SG")
		)
		(pad "9" smd rect
			(at 0 0 90)
			(size 0.9906 1.8034)
			(layers "F.Cu" "F.Mask" "F.Paste")
			(net "SG")
		)
	)
)
